(kicad_pcb
	(version 20260206)
	(generator "pcbnew")
	(generator_version "10.0")
	(general
		(thickness 1.6)
		(legacy_teardrops no)
	)
	(paper "A4")
	(title_block
		(title "Bryce Canyon_IOM_IOC_16318-2_OCP.brd")
		(comment 1 "Bryce Canyon / footprints 755-762 of 1605")
	)
	(layers
		(0 "F.Cu" signal "TOP")
		(4 "In1.Cu" signal "L2GND")
		(6 "In2.Cu" signal "L3")
		(8 "In3.Cu" signal "L4VCC")
		(10 "In4.Cu" signal "L5VCC")
		(12 "In5.Cu" signal "L6")
		(14 "In6.Cu" signal "L7GND")
		(2 "B.Cu" signal "BOTTOM")
		(9 "F.Adhes" user "F.Adhesive")
		(11 "B.Adhes" user "B.Adhesive")
		(13 "F.Paste" user "Package Geometry/Pastemask Top")
		(15 "B.Paste" user "Package Geometry/Pastemask Bottom")
		(5 "F.SilkS" user "Ref Des/Silkscreen Top")
		(7 "B.SilkS" user "Ref Des/Silkscreen Bottom")
		(1 "F.Mask" user "Board Geometry/Soldermask Top")
		(3 "B.Mask" user "Board Geometry/Soldermask Bottom")
		(17 "Dwgs.User" user "User.Drawings")
		(19 "Cmts.User" user "User.Comments")
		(21 "Eco1.User" user "User.Eco1")
		(23 "Eco2.User" user "User.Eco2")
		(25 "Edge.Cuts" user "Board Geometry/Outline")
		(27 "Margin" user)
		(31 "F.CrtYd" user "Package Geometry/Place Bound Top")
		(29 "B.CrtYd" user "Package Geometry/Place Bound Bottom")
		(35 "F.Fab" user "Ref Des/Assembly Top")
		(33 "B.Fab" user "Ref Des/Assembly Bottom")
	)
	(footprint ""
		(layer "F.Cu")
		(at 39.839646 -180.64861 90)
		(property "Reference" "R498"
			(at 0 0 90)
			(layer "F.SilkS")
			(hide yes)
			(effects
				(font
					(size 1.27 1.27)
				)
			)
		)
		(property "Value" "0R2J-2-GP"
			(at 0.064008 -3.993896 90)
			(unlocked yes)
			(layer "F.Fab")
			(hide yes)
			(effects
				(font
					(size 1.016 1.016)
					(thickness 0.1524)
				)
			)
		)
		(property "Device Type" "R402H16"
			(at 0.064008 -5.517896 90)
			(unlocked yes)
			(layer "F.Fab")
			(hide yes)
			(effects
				(font
					(size 1.016 1.016)
					(thickness 0.1524)
				)
			)
		)
		(duplicate_pad_numbers_are_jumpers no)
		(fp_line
			(start 0.508 -0.9398)
			(end -0.508 -0.9398)
			(stroke
				(width 0.1524)
				(type default)
			)
			(layer "F.SilkS")
		)
		(fp_line
			(start -0.508 -0.9398)
			(end -0.508 0.9398)
			(stroke
				(width 0.1524)
				(type default)
			)
			(layer "F.SilkS")
		)
		(fp_rect
			(start -0.508 0.9398)
			(end 0.508 -0.9398)
			(stroke
				(width 0)
				(type default)
			)
			(fill no)
			(layer "F.CrtYd")
		)
		(fp_rect
			(start -0.508 0.9398)
			(end 0.508 -0.9398)
			(stroke
				(width 0)
				(type default)
			)
			(fill no)
			(layer "F.Fab")
		)
		(pad "1" smd custom
			(at 0 -0.4445 90)
			(size 0.1397 0.1397)
			(layers "F.Cu" "F.Mask" "F.Paste")
			(net "P3V3_STBY_ROVP")
			(options
				(clearance outline)
				(anchor circle)
			)
			(primitives
				(gr_poly
					(pts
						(arc
							(start -0.1778 -0.2794)
							(mid -0.249642 -0.249642)
							(end -0.2794 -0.1778)
						)
						(arc
							(start -0.2794 0.1778)
							(mid -0.249642 0.249642)
							(end -0.1778 0.2794)
						)
						(arc
							(start 0.1778 0.2794)
							(mid 0.249642 0.249642)
							(end 0.2794 0.1778)
						)
						(arc
							(start 0.2794 -0.1778)
							(mid 0.249642 -0.249642)
							(end 0.1778 -0.2794)
						)
					)
					(width 0)
					(fill yes)
				)
			)
		)
		(pad "2" smd custom
			(at 0 0.4445 90)
			(size 0.1397 0.1397)
			(layers "F.Cu" "F.Mask" "F.Paste")
			(net "AGND_P3V3_STBY")
			(options
				(clearance outline)
				(anchor circle)
			)
			(primitives
				(gr_poly
					(pts
						(arc
							(start -0.1778 -0.2794)
							(mid -0.249642 -0.249642)
							(end -0.2794 -0.1778)
						)
						(arc
							(start -0.2794 0.1778)
							(mid -0.249642 0.249642)
							(end -0.1778 0.2794)
						)
						(arc
							(start 0.1778 0.2794)
							(mid 0.249642 0.249642)
							(end 0.2794 0.1778)
						)
						(arc
							(start 0.2794 -0.1778)
							(mid 0.249642 -0.249642)
							(end 0.1778 -0.2794)
						)
					)
					(width 0)
					(fill yes)
				)
			)
		)
	)
	(footprint ""
		(layer "F.Cu")
		(at 168.6306 -108.1532 -90)
		(property "Reference" "C465"
			(at 0 0 270)
			(layer "F.SilkS")
			(hide yes)
			(effects
				(font
					(size 1.27 1.27)
				)
			)
		)
		(property "Value" "SC1U16V2KX-7-GP"
			(at 1.7526 -1.6002 270)
			(unlocked yes)
			(layer "F.Fab")
			(hide yes)
			(effects
				(font
					(size 1.016 1.016)
					(thickness 0.1524)
				)
			)
		)
		(property "Device Type" "C402-TO0D2H24"
			(at 1.7526 -3.1242 270)
			(unlocked yes)
			(layer "F.Fab")
			(hide yes)
			(effects
				(font
					(size 1.016 1.016)
					(thickness 0.1524)
				)
			)
		)
		(duplicate_pad_numbers_are_jumpers no)
		(fp_rect
			(start -0.4826 0.889)
			(end 0.4826 -0.889)
			(stroke
				(width 0)
				(type default)
			)
			(fill no)
			(layer "F.CrtYd")
		)
		(fp_rect
			(start -0.4826 0.889)
			(end 0.4826 -0.889)
			(stroke
				(width 0)
				(type default)
			)
			(fill no)
			(layer "F.Fab")
		)
		(pad "1" smd custom
			(at 0 -0.4572 270)
			(size 0.1524 0.1524)
			(layers "F.Cu" "F.Mask" "F.Paste")
			(net "P1V8")
			(options
				(clearance outline)
				(anchor circle)
			)
			(primitives
				(gr_poly
					(pts
						(arc
							(start -0.254 0.3048)
							(mid -0.325842 0.275042)
							(end -0.3556 0.2032)
						)
						(arc
							(start -0.3556 -0.2032)
							(mid -0.325842 -0.275042)
							(end -0.254 -0.3048)
						)
						(arc
							(start 0.254 -0.3048)
							(mid 0.325842 -0.275042)
							(end 0.3556 -0.2032)
						)
						(arc
							(start 0.3556 0.2032)
							(mid 0.325842 0.275042)
							(end 0.254 0.3048)
						)
					)
					(width 0)
					(fill yes)
				)
			)
		)
		(pad "2" smd custom
			(at 0 0.4572 270)
			(size 0.1524 0.1524)
			(layers "F.Cu" "F.Mask" "F.Paste")
			(net "GND")
			(options
				(clearance outline)
				(anchor circle)
			)
			(primitives
				(gr_poly
					(pts
						(arc
							(start -0.254 0.3048)
							(mid -0.325842 0.275042)
							(end -0.3556 0.2032)
						)
						(arc
							(start -0.3556 -0.2032)
							(mid -0.325842 -0.275042)
							(end -0.254 -0.3048)
						)
						(arc
							(start 0.254 -0.3048)
							(mid 0.325842 -0.275042)
							(end 0.3556 -0.2032)
						)
						(arc
							(start 0.3556 0.2032)
							(mid 0.325842 0.275042)
							(end 0.254 0.3048)
						)
					)
					(width 0)
					(fill yes)
				)
			)
		)
	)
	(footprint ""
		(layer "F.Cu")
		(at 78.122018 -90.155268 90)
		(property "Reference" "VIA7"
			(at 0 0 90)
			(layer "F.SilkS")
			(hide yes)
			(effects
				(font
					(size 1.27 1.27)
				)
			)
		)
		(property "Value" "85OHM-8L-1D6MM-L16L18-GP"
			(at 4.064 0.6096 90)
			(unlocked yes)
			(layer "F.Fab")
			(hide yes)
			(effects
				(font
					(size 1.016 1.016)
					(thickness 0.1524)
				)
			)
		)
		(property "Device Type" "VIA-PCIE-4P-368076"
			(at 4.064 -0.9144 90)
			(unlocked yes)
			(layer "F.Fab")
			(hide yes)
			(effects
				(font
					(size 1.016 1.016)
					(thickness 0.1524)
				)
			)
		)
		(duplicate_pad_numbers_are_jumpers no)
		(fp_rect
			(start -1.8415 0.381)
			(end 1.8415 -0.381)
			(stroke
				(width 0)
				(type default)
			)
			(fill no)
			(layer "F.CrtYd")
		)
		(fp_rect
			(start -1.8415 0.381)
			(end 1.8415 -0.381)
			(stroke
				(width 0)
				(type default)
			)
			(fill no)
			(layer "F.Fab")
		)
		(pad "1" thru_hole circle
			(at -1.4605 0 90)
			(size 0.508 0.508)
			(drill 0.254)
			(layers "*.Cu" "*.Mask")
			(remove_unused_layers no)
			(net "GND")
			(clearance 0.127)
			(thermal_gap 0.127)
		)
		(pad "2" thru_hole circle
			(at -0.4445 0 90)
			(size 0.508 0.508)
			(drill 0.254)
			(layers "*.Cu" "*.Mask")
			(remove_unused_layers no)
			(net "PCIE_COMP_TO_IOM_22_DP")
			(clearance 0.127)
			(thermal_gap 0.127)
		)
		(pad "3" thru_hole circle
			(at 0.4445 0 90)
			(size 0.508 0.508)
			(drill 0.254)
			(layers "*.Cu" "*.Mask")
			(remove_unused_layers no)
			(net "PCIE_COMP_TO_IOM_22_DN")
			(clearance 0.127)
			(thermal_gap 0.127)
		)
		(pad "4" thru_hole circle
			(at 1.4605 0 90)
			(size 0.508 0.508)
			(drill 0.254)
			(layers "*.Cu" "*.Mask")
			(remove_unused_layers no)
			(net "GND")
			(clearance 0.127)
			(thermal_gap 0.127)
		)
	)
	(footprint ""
		(layer "F.Cu")
		(at 128.917446 -10.732008 -90)
		(property "Reference" "R710"
			(at 0 0 270)
			(layer "F.SilkS")
			(hide yes)
			(effects
				(font
					(size 1.27 1.27)
				)
			)
		)
		(property "Value" "0R5J-5-GP"
			(at 0 -8.9535 270)
			(unlocked yes)
			(layer "F.Fab")
			(hide yes)
			(effects
				(font
					(size 1.27 1.016)
					(thickness 0.1524)
				)
			)
		)
		(property "Device Type" "R805H24"
			(at 0 -10.6299 270)
			(unlocked yes)
			(layer "F.Fab")
			(hide yes)
			(effects
				(font
					(size 1.27 1.016)
					(thickness 0.1524)
				)
			)
		)
		(duplicate_pad_numbers_are_jumpers no)
		(fp_line
			(start -0.889 1.7018)
			(end 0.889 1.7018)
			(stroke
				(width 0.1524)
				(type default)
			)
			(layer "F.SilkS")
		)
		(fp_line
			(start 0.889 1.7018)
			(end 0.889 -0.508)
			(stroke
				(width 0.1524)
				(type default)
			)
			(layer "F.SilkS")
		)
		(fp_line
			(start -0.889 0.0762)
			(end -0.889 1.7018)
			(stroke
				(width 0.1524)
				(type default)
			)
			(layer "F.SilkS")
		)
		(fp_line
			(start -0.889 -1.7018)
			(end -0.889 0.2794)
			(stroke
				(width 0.1524)
				(type default)
			)
			(layer "F.SilkS")
		)
		(fp_line
			(start 0.889 -1.7018)
			(end 0.889 -0.381)
			(stroke
				(width 0.1524)
				(type default)
			)
			(layer "F.SilkS")
		)
		(fp_line
			(start 0.889 -1.7018)
			(end -0.889 -1.7018)
			(stroke
				(width 0.1524)
				(type default)
			)
			(layer "F.SilkS")
		)
		(fp_poly
			(pts
				(xy 0.9652 -1.778) (xy 0.9652 1.778) (xy -0.9652 1.778) (xy -0.9652 -1.778)
			)
			(stroke
				(width 0)
				(type default)
			)
			(fill no)
			(layer "F.CrtYd")
		)
		(fp_rect
			(start -0.9652 1.778)
			(end 0.9652 -1.778)
			(stroke
				(width 0)
				(type default)
			)
			(fill no)
			(layer "F.Fab")
		)
		(pad "1" smd rect
			(at 0 -0.9652 270)
			(size 1.397 1.143)
			(layers "F.Cu" "F.Mask" "F.Paste")
			(net "MB0_CM_GATE_R")
		)
		(pad "2" smd rect
			(at 0 0.9652 270)
			(size 1.397 1.143)
			(layers "F.Cu" "F.Mask" "F.Paste")
			(net "MB0_CM_GATE")
		)
	)
	(footprint ""
		(layer "F.Cu")
		(at 172.9486 -136.2964 -90)
		(property "Reference" "C151"
			(at 0 0 270)
			(layer "F.SilkS")
			(hide yes)
			(effects
				(font
					(size 1.27 1.27)
				)
			)
		)
		(property "Value" "SC10U16V5KX-7-GP-U"
			(at -0.0762 -6.1214 270)
			(unlocked yes)
			(layer "F.Fab")
			(hide yes)
			(effects
				(font
					(size 1.016 1.016)
					(thickness 0.1524)
				)
			)
		)
		(property "Device Type" "C805H58"
			(at -0.0762 -8.1534 270)
			(unlocked yes)
			(layer "F.Fab")
			(hide yes)
			(effects
				(font
					(size 1.016 1.016)
					(thickness 0.1524)
				)
			)
		)
		(duplicate_pad_numbers_are_jumpers no)
		(fp_line
			(start 0.635 0)
			(end -0.635 0)
			(stroke
				(width 0.508)
				(type default)
			)
			(layer "F.SilkS")
		)
		(fp_rect
			(start -0.9652 1.778)
			(end 0.9652 -1.778)
			(stroke
				(width 0)
				(type default)
			)
			(fill no)
			(layer "F.CrtYd")
		)
		(fp_poly
			(pts
				(xy -0.9652 -1.778) (xy 0.9652 -1.778) (xy 0.9652 1.778) (xy -0.9652 1.778)
			)
			(stroke
				(width 0)
				(type default)
			)
			(fill no)
			(layer "F.Fab")
		)
		(pad "1" smd rect
			(at 0 -0.9652 270)
			(size 1.397 1.143)
			(layers "F.Cu" "F.Mask" "F.Paste")
			(net "P12V_STBY_VIN_PU1")
		)
		(pad "2" smd rect
			(at 0 0.9652 270)
			(size 1.397 1.143)
			(layers "F.Cu" "F.Mask" "F.Paste")
			(net "GND")
		)
	)
	(footprint ""
		(layer "F.Cu")
		(at 167.4368 -138.0998 180)
		(property "Reference" "R512"
			(at 0 0 180)
			(layer "F.SilkS")
			(hide yes)
			(effects
				(font
					(size 1.27 1.27)
				)
			)
		)
		(property "Value" "0R6J-3-GP"
			(at -0.0508 -4.8514 180)
			(unlocked yes)
			(layer "F.Fab")
			(hide yes)
			(effects
				(font
					(size 1.016 1.016)
					(thickness 0.1524)
				)
			)
		)
		(property "Device Type" "R1206H28"
			(at 0 -6.3754 180)
			(unlocked yes)
			(layer "F.Fab")
			(hide yes)
			(effects
				(font
					(size 1.016 1.016)
					(thickness 0.1524)
				)
			)
		)
		(duplicate_pad_numbers_are_jumpers no)
		(fp_line
			(start 1.016 2.2352)
			(end -1.016 2.2352)
			(stroke
				(width 0.1524)
				(type default)
			)
			(layer "F.SilkS")
		)
		(fp_line
			(start 1.016 -2.2352)
			(end 1.016 2.2352)
			(stroke
				(width 0.1524)
				(type default)
			)
			(layer "F.SilkS")
		)
		(fp_line
			(start -1.016 2.2352)
			(end -1.016 -2.2352)
			(stroke
				(width 0.1524)
				(type default)
			)
			(layer "F.SilkS")
		)
		(fp_line
			(start -1.016 -2.2352)
			(end 1.016 -2.2352)
			(stroke
				(width 0.1524)
				(type default)
			)
			(layer "F.SilkS")
		)
		(fp_rect
			(start -1.0922 2.3114)
			(end 1.0922 -2.3114)
			(stroke
				(width 0)
				(type default)
			)
			(fill no)
			(layer "F.CrtYd")
		)
		(fp_poly
			(pts
				(xy -1.0922 -2.3114) (xy 1.0922 -2.3114) (xy 1.0922 2.3114) (xy -1.0922 2.3114)
			)
			(stroke
				(width 0)
				(type default)
			)
			(fill no)
			(layer "F.Fab")
		)
		(pad "1" smd rect
			(at 0 -1.397 180)
			(size 1.651 1.27)
			(layers "F.Cu" "F.Mask" "F.Paste")
			(net "P12V_STBY_VIN_PU4")
		)
		(pad "2" smd rect
			(at 0 1.397 180)
			(size 1.651 1.27)
			(layers "F.Cu" "F.Mask" "F.Paste")
			(net "P12V_STBY")
		)
	)
	(footprint ""
		(layer "F.Cu")
		(at 74.426572 -173.774862 -90)
		(property "Reference" "R505"
			(at 0 0 270)
			(layer "F.SilkS")
			(hide yes)
			(effects
				(font
					(size 1.27 1.27)
				)
			)
		)
		(property "Value" "3K57R2F-GP"
			(at 0.064008 -3.993896 270)
			(unlocked yes)
			(layer "F.Fab")
			(hide yes)
			(effects
				(font
					(size 1.016 1.016)
					(thickness 0.1524)
				)
			)
		)
		(property "Device Type" "R402H16"
			(at 0.064008 -5.517896 270)
			(unlocked yes)
			(layer "F.Fab")
			(hide yes)
			(effects
				(font
					(size 1.016 1.016)
					(thickness 0.1524)
				)
			)
		)
		(duplicate_pad_numbers_are_jumpers no)
		(fp_line
			(start -0.508 -0.9398)
			(end -0.508 0.9398)
			(stroke
				(width 0.1524)
				(type default)
			)
			(layer "F.SilkS")
		)
		(fp_line
			(start 0.508 -0.9398)
			(end -0.508 -0.9398)
			(stroke
				(width 0.1524)
				(type default)
			)
			(layer "F.SilkS")
		)
		(fp_rect
			(start -0.508 0.9398)
			(end 0.508 -0.9398)
			(stroke
				(width 0)
				(type default)
			)
			(fill no)
			(layer "F.CrtYd")
		)
		(fp_rect
			(start -0.508 0.9398)
			(end 0.508 -0.9398)
			(stroke
				(width 0)
				(type default)
			)
			(fill no)
			(layer "F.Fab")
		)
		(pad "1" smd custom
			(at 0 -0.4445 270)
			(size 0.1397 0.1397)
			(layers "F.Cu" "F.Mask" "F.Paste")
			(net "TPS74801_P2V5_STBY_OUT")
			(options
				(clearance outline)
				(anchor circle)
			)
			(primitives
				(gr_poly
					(pts
						(arc
							(start -0.1778 -0.2794)
							(mid -0.249642 -0.249642)
							(end -0.2794 -0.1778)
						)
						(arc
							(start -0.2794 0.1778)
							(mid -0.249642 0.249642)
							(end -0.1778 0.2794)
						)
						(arc
							(start 0.1778 0.2794)
							(mid 0.249642 0.249642)
							(end 0.2794 0.1778)
						)
						(arc
							(start 0.2794 -0.1778)
							(mid 0.249642 -0.249642)
							(end 0.1778 -0.2794)
						)
					)
					(width 0)
					(fill yes)
				)
			)
		)
		(pad "2" smd custom
			(at 0 0.4445 270)
			(size 0.1397 0.1397)
			(layers "F.Cu" "F.Mask" "F.Paste")
			(net "TPS74801_P2V5_STBY_FB")
			(options
				(clearance outline)
				(anchor circle)
			)
			(primitives
				(gr_poly
					(pts
						(arc
							(start -0.1778 -0.2794)
							(mid -0.249642 -0.249642)
							(end -0.2794 -0.1778)
						)
						(arc
							(start -0.2794 0.1778)
							(mid -0.249642 0.249642)
							(end -0.1778 0.2794)
						)
						(arc
							(start 0.1778 0.2794)
							(mid 0.249642 0.249642)
							(end 0.2794 0.1778)
						)
						(arc
							(start 0.2794 -0.1778)
							(mid 0.249642 -0.249642)
							(end 0.1778 -0.2794)
						)
					)
					(width 0)
					(fill yes)
				)
			)
		)
	)
	(footprint ""
		(layer "F.Cu")
		(at 61.3664 -147.5994 -90)
		(property "Reference" "R164"
			(at 0 0 270)
			(layer "F.SilkS")
			(hide yes)
			(effects
				(font
					(size 1.27 1.27)
				)
			)
		)
		(property "Value" "0R2J-2-GP"
			(at 0.064008 -3.993896 270)
			(unlocked yes)
			(layer "F.Fab")
			(hide yes)
			(effects
				(font
					(size 1.016 1.016)
					(thickness 0.1524)
				)
			)
		)
		(property "Device Type" "R402H16"
			(at 0.064008 -5.517896 270)
			(unlocked yes)
			(layer "F.Fab")
			(hide yes)
			(effects
				(font
					(size 1.016 1.016)
					(thickness 0.1524)
				)
			)
		)
		(duplicate_pad_numbers_are_jumpers no)
		(fp_line
			(start -0.508 -0.9398)
			(end -0.508 0.9398)
			(stroke
				(width 0.1524)
				(type default)
			)
			(layer "F.SilkS")
		)
		(fp_line
			(start 0.508 -0.9398)
			(end -0.508 -0.9398)
			(stroke
				(width 0.1524)
				(type default)
			)
			(layer "F.SilkS")
		)
		(fp_rect
			(start -0.508 0.9398)
			(end 0.508 -0.9398)
			(stroke
				(width 0)
				(type default)
			)
			(fill no)
			(layer "F.CrtYd")
		)
		(fp_rect
			(start -0.508 0.9398)
			(end 0.508 -0.9398)
			(stroke
				(width 0)
				(type default)
			)
			(fill no)
			(layer "F.Fab")
		)
		(pad "1" smd custom
			(at 0 -0.4445 270)
			(size 0.1397 0.1397)
			(layers "F.Cu" "F.Mask" "F.Paste")
			(net "I2C_BMC_COMP_SCL_OUT")
			(options
				(clearance outline)
				(anchor circle)
			)
			(primitives
				(gr_poly
					(pts
						(arc
							(start -0.1778 -0.2794)
							(mid -0.249642 -0.249642)
							(end -0.2794 -0.1778)
						)
						(arc
							(start -0.2794 0.1778)
							(mid -0.249642 0.249642)
							(end -0.1778 0.2794)
						)
						(arc
							(start 0.1778 0.2794)
							(mid 0.249642 0.249642)
							(end 0.2794 0.1778)
						)
						(arc
							(start 0.2794 -0.1778)
							(mid 0.249642 -0.249642)
							(end 0.1778 -0.2794)
						)
					)
					(width 0)
					(fill yes)
				)
			)
		)
		(pad "2" smd custom
			(at 0 0.4445 270)
			(size 0.1397 0.1397)
			(layers "F.Cu" "F.Mask" "F.Paste")
			(net "BMC_SMB4_CLK")
			(options
				(clearance outline)
				(anchor circle)
			)
			(primitives
				(gr_poly
					(pts
						(arc
							(start -0.1778 -0.2794)
							(mid -0.249642 -0.249642)
							(end -0.2794 -0.1778)
						)
						(arc
							(start -0.2794 0.1778)
							(mid -0.249642 0.249642)
							(end -0.1778 0.2794)
						)
						(arc
							(start 0.1778 0.2794)
							(mid 0.249642 0.249642)
							(end 0.2794 0.1778)
						)
						(arc
							(start 0.2794 -0.1778)
							(mid 0.249642 -0.249642)
							(end 0.1778 -0.2794)
						)
					)
					(width 0)
					(fill yes)
				)
			)
		)
	)
)
